# T6G (Grand Teton) — schematic netlist excerpt (pin names and nets, part order shuffled) for the footprints in the layout excerpt that follows; sources: Cadence DE-HDL packaged netlist, KiCad conversion of 04192023_DAF0TMB3IC0_F0TG_MB_C_brd_V02_OCP.brd

R1785  Q_RES  4.7K 1% CHIP  pkg 0402LF  page 257 : A = P3V3_AUX_ADC ; B = GND
R459  Q_RES  33 5% CHIP  pkg 0402LF  page 29 : A = SPI_CPU0_CS0_N ; B = SPI_CPU0_R_CS0_N

(kicad_pcb
	(version 20260206)
	(generator "pcbnew")
	(generator_version "10.0")
	(general
		(thickness 1.6)
		(legacy_teardrops no)
	)
	(paper "A4")
	(title_block
		(title "04192023_DAF0TMB3IC0_F0TG_MB_C_brd_V02_OCP.brd")
		(comment 1 "Grand Teton / footprints 1642-1643 of 8354")
	)
	(layers
		(0 "F.Cu" signal "TOP")
		(4 "In1.Cu" signal "GND")
		(6 "In2.Cu" signal "IN1")
		(8 "In3.Cu" signal "GND1")
		(10 "In4.Cu" signal "IN2")
		(12 "In5.Cu" signal "GND2")
		(14 "In6.Cu" signal "IN3")
		(16 "In7.Cu" signal "GND3")
		(18 "In8.Cu" signal "VCC")
		(20 "In9.Cu" signal "VCC1")
		(22 "In10.Cu" signal "GND4")
		(24 "In11.Cu" signal "IN4")
		(26 "In12.Cu" signal "GND5")
		(28 "In13.Cu" signal "IN5")
		(30 "In14.Cu" signal "GND6")
		(32 "In15.Cu" signal "IN6")
		(34 "In16.Cu" signal "GND7")
		(2 "B.Cu" signal "BOTTOM")
		(9 "F.Adhes" user "F.Adhesive")
		(11 "B.Adhes" user "B.Adhesive")
		(13 "F.Paste" user "Package Geometry/Pastemask Top")
		(15 "B.Paste" user "Package Geometry/Pastemask Bottom")
		(5 "F.SilkS" user "Ref Des/Silkscreen Top")
		(7 "B.SilkS" user "Ref Des/Silkscreen Bottom")
		(1 "F.Mask" user "Board Geometry/Soldermask Top")
		(3 "B.Mask" user "Board Geometry/Soldermask Bottom")
		(17 "Dwgs.User" user "User.Drawings")
		(19 "Cmts.User" user "User.Comments")
		(21 "Eco1.User" user "User.Eco1")
		(23 "Eco2.User" user "User.Eco2")
		(25 "Edge.Cuts" user "Board Geometry/Outline")
		(27 "Margin" user)
		(31 "F.CrtYd" user "Package Geometry/Place Bound Top")
		(29 "B.CrtYd" user "Package Geometry/Place Bound Bottom")
		(35 "F.Fab" user "Ref Des/Assembly Top")
		(33 "B.Fab" user "Ref Des/Assembly Bottom")
	)
	(footprint ""
		(layer "F.Cu")
		(at 400.22272 -330.575666 90)
		(property "Reference" "R459"
			(at 0 0 90)
			(layer "F.SilkS")
			(hide yes)
			(effects
				(font
					(size 1.27 1.27)
				)
			)
		)
		(property "Value" ""
			(at 0 0 90)
			(layer "F.Fab")
			(effects
				(font
					(size 1.27 1.27)
				)
			)
		)
		(duplicate_pad_numbers_are_jumpers no)
		(fp_line
			(start 0.7874 -0.4064)
			(end 0.7874 0.4064)
			(stroke
				(width 0.1524)
				(type default)
			)
			(layer "F.SilkS")
		)
		(fp_line
			(start -0.7874 -0.4064)
			(end 0.7874 -0.4064)
			(stroke
				(width 0.1524)
				(type default)
			)
			(layer "F.SilkS")
		)
		(fp_line
			(start 0.7874 0.4064)
			(end -0.7874 0.4064)
			(stroke
				(width 0.1524)
				(type default)
			)
			(layer "F.SilkS")
		)
		(fp_line
			(start -0.7874 0.4064)
			(end -0.7874 -0.4064)
			(stroke
				(width 0.1524)
				(type default)
			)
			(layer "F.SilkS")
		)
		(fp_line
			(start -0.12065 -0.305054)
			(end -0.12065 -0.2794)
			(stroke
				(width 0.1)
				(type default)
			)
			(layer "F.Fab")
		)
		(fp_line
			(start -0.67945 -0.305054)
			(end -0.12065 -0.305054)
			(stroke
				(width 0.1)
				(type default)
			)
			(layer "F.Fab")
		)
		(fp_line
			(start 0.67945 -0.3048)
			(end 0.67945 0.3048)
			(stroke
				(width 0.1)
				(type default)
			)
			(layer "F.Fab")
		)
		(fp_line
			(start 0.12065 -0.3048)
			(end 0.67945 -0.3048)
			(stroke
				(width 0.1)
				(type default)
			)
			(layer "F.Fab")
		)
		(fp_line
			(start 0.12065 -0.2794)
			(end 0.12065 -0.3048)
			(stroke
				(width 0.1)
				(type default)
			)
			(layer "F.Fab")
		)
		(fp_line
			(start -0.12065 -0.2794)
			(end 0.12065 -0.2794)
			(stroke
				(width 0.1)
				(type default)
			)
			(layer "F.Fab")
		)
		(fp_line
			(start 0.120396 0.2794)
			(end -0.12065 0.2794)
			(stroke
				(width 0.1)
				(type default)
			)
			(layer "F.Fab")
		)
		(fp_line
			(start -0.12065 0.2794)
			(end -0.12065 0.3048)
			(stroke
				(width 0.1)
				(type default)
			)
			(layer "F.Fab")
		)
		(fp_line
			(start 0.67945 0.3048)
			(end 0.120396 0.3048)
			(stroke
				(width 0.1)
				(type default)
			)
			(layer "F.Fab")
		)
		(fp_line
			(start 0.120396 0.3048)
			(end 0.120396 0.2794)
			(stroke
				(width 0.1)
				(type default)
			)
			(layer "F.Fab")
		)
		(fp_line
			(start -0.12065 0.3048)
			(end -0.67945 0.3048)
			(stroke
				(width 0.1)
				(type default)
			)
			(layer "F.Fab")
		)
		(fp_line
			(start -0.67945 0.3048)
			(end -0.67945 -0.305054)
			(stroke
				(width 0.1)
				(type default)
			)
			(layer "F.Fab")
		)
		(pad "1" smd circle
			(at -0.40005 0 90)
			(size 0 0)
			(layers "F.Cu" "F.Mask" "F.Paste")
			(net "SPI_CPU0_CS0_N")
		)
		(pad "2" smd circle
			(at 0.40005 0 90)
			(size 0 0)
			(layers "F.Cu" "F.Mask" "F.Paste")
			(net "SPI_CPU0_R_CS0_N")
		)
	)
	(footprint ""
		(layer "F.Cu")
		(at 327.179178 -41.160954)
		(property "Reference" "R1785"
			(at 0 0 0)
			(layer "F.SilkS")
			(hide yes)
			(effects
				(font
					(size 1.27 1.27)
				)
			)
		)
		(property "Value" ""
			(at 0 0 0)
			(layer "F.Fab")
			(effects
				(font
					(size 1.27 1.27)
				)
			)
		)
		(duplicate_pad_numbers_are_jumpers no)
		(fp_line
			(start -0.7874 -0.4064)
			(end 0.7874 -0.4064)
			(stroke
				(width 0.1524)
				(type default)
			)
			(layer "F.SilkS")
		)
		(fp_line
			(start -0.7874 0.4064)
			(end -0.7874 -0.4064)
			(stroke
				(width 0.1524)
				(type default)
			)
			(layer "F.SilkS")
		)
		(fp_line
			(start 0.7874 -0.4064)
			(end 0.7874 0.4064)
			(stroke
				(width 0.1524)
				(type default)
			)
			(layer "F.SilkS")
		)
		(fp_line
			(start 0.7874 0.4064)
			(end -0.7874 0.4064)
			(stroke
				(width 0.1524)
				(type default)
			)
			(layer "F.SilkS")
		)
		(fp_line
			(start -0.67945 -0.305054)
			(end -0.12065 -0.305054)
			(stroke
				(width 0.1)
				(type default)
			)
			(layer "F.Fab")
		)
		(fp_line
			(start -0.67945 0.3048)
			(end -0.67945 -0.305054)
			(stroke
				(width 0.1)
				(type default)
			)
			(layer "F.Fab")
		)
		(fp_line
			(start -0.12065 -0.305054)
			(end -0.12065 -0.2794)
			(stroke
				(width 0.1)
				(type default)
			)
			(layer "F.Fab")
		)
		(fp_line
			(start -0.12065 -0.2794)
			(end 0.12065 -0.2794)
			(stroke
				(width 0.1)
				(type default)
			)
			(layer "F.Fab")
		)
		(fp_line
			(start -0.12065 0.2794)
			(end -0.12065 0.3048)
			(stroke
				(width 0.1)
				(type default)
			)
			(layer "F.Fab")
		)
		(fp_line
			(start -0.12065 0.3048)
			(end -0.67945 0.3048)
			(stroke
				(width 0.1)
				(type default)
			)
			(layer "F.Fab")
		)
		(fp_line
			(start 0.120396 0.2794)
			(end -0.12065 0.2794)
			(stroke
				(width 0.1)
				(type default)
			)
			(layer "F.Fab")
		)
		(fp_line
			(start 0.120396 0.3048)
			(end 0.120396 0.2794)
			(stroke
				(width 0.1)
				(type default)
			)
			(layer "F.Fab")
		)
		(fp_line
			(start 0.12065 -0.3048)
			(end 0.67945 -0.3048)
			(stroke
				(width 0.1)
				(type default)
			)
			(layer "F.Fab")
		)
		(fp_line
			(start 0.12065 -0.2794)
			(end 0.12065 -0.3048)
			(stroke
				(width 0.1)
				(type default)
			)
			(layer "F.Fab")
		)
		(fp_line
			(start 0.67945 -0.3048)
			(end 0.67945 0.3048)
			(stroke
				(width 0.1)
				(type default)
			)
			(layer "F.Fab")
		)
		(fp_line
			(start 0.67945 0.3048)
			(end 0.120396 0.3048)
			(stroke
				(width 0.1)
				(type default)
			)
			(layer "F.Fab")
		)
		(pad "1" smd circle
			(at -0.40005 0)
			(size 0 0)
			(layers "F.Cu" "F.Mask" "F.Paste")
			(net "P3V3_AUX_ADC")
		)
		(pad "2" smd circle
			(at 0.40005 0)
			(size 0 0)
			(layers "F.Cu" "F.Mask" "F.Paste")
			(net "GND")
		)
	)
)
